(kicad_pcb
	(version 20221018)
	(generator pcbnew)
	(general
    (thickness 0.908)
  )
	(paper "A4")
	(title_block
    (title "HDMI-MIPI Bridge")
    (date "2024-04-24")
    (rev "1.3.2")
		(comment 9 "footprints 97-106 of 121")
	)
	(layers
    (0 "F.Cu" signal)
    (1 "In1.Cu" signal)
    (2 "In2.Cu" signal)
    (31 "B.Cu" signal)
    (32 "B.Adhes" user "B.Adhesive")
    (33 "F.Adhes" user "F.Adhesive")
    (34 "B.Paste" user)
    (35 "F.Paste" user)
    (36 "B.SilkS" user "B.Silkscreen")
    (37 "F.SilkS" user "F.Silkscreen")
    (38 "B.Mask" user)
    (39 "F.Mask" user)
    (40 "Dwgs.User" user "User.Drawings")
    (41 "Cmts.User" user "User.Comments")
    (42 "Eco1.User" user "User.Eco1")
    (43 "Eco2.User" user "User.Eco2")
    (44 "Edge.Cuts" user)
    (45 "Margin" user)
    (46 "B.CrtYd" user "B.Courtyard")
    (47 "F.CrtYd" user "F.Courtyard")
    (48 "B.Fab" user)
    (49 "F.Fab" user)
  )
	(footprint "antmicro-footprints:R_0603_1608Metric" (layer "B.Cu")
    (at 154.7 113.65 180)
    (descr "Resistor SMD 0603")
    (tags "resistor SMD 0603")
    (property "Author" "Antmicro")
    (property "Current" "1A")
    (property "License" "Apache-2.0")
    (property "MPN" "CR0603-J/-000ELF")
    (property "Manufacturer" "Bourns")
    (property "Public" "False")
    (property "Sheetfile" "channel2.kicad_sch")
    (property "Sheetname" "Channel 2")
    (property "Tolerance" "")
    (property "Val" "0R")
    (property "ki_description" "Zero Ohm Resistor, Jumper, 0603 [1608 Metric], Thick Film, 100 mW, 1 A, Surface Mount Device, CR")
    (property "ki_keywords" "0603, SMT, RESISTOR, PASSIVE")
    (attr smd)
    (fp_text reference "R20" (at 1 -0.45) (layer "B.SilkS")
        (effects (font (size 0.7 0.7) (thickness 0.15)) (justify left bottom mirror))
    )
    (fp_text value "R_0R_0603" (at 0 -1.6) (layer "B.Fab")
        (effects (font (size 0.7 0.7) (thickness 0.15)) (justify left bottom mirror))
    )
    (fp_text user "${REFERENCE}" (at -1.25 -3.898) (layer "B.Fab") hide
        (effects (font (size 0.7 0.7) (thickness 0.15)) (justify left bottom mirror))
    )
    (fp_text user "Author: Antmicro" (at -1.25 -4.9) (layer "B.Fab") hide
        (effects (font (size 0.7 0.7) (thickness 0.15)) (justify left bottom mirror))
    )
    (fp_text user "License: Apache-2.0" (at -1.25 -5.9) (layer "B.Fab") hide
        (effects (font (size 0.7 0.7) (thickness 0.15)) (justify left bottom mirror))
    )
    (fp_line (start -0.15 -0.4) (end 0.15 -0.4)
      (stroke (width 0.15) (type solid)) (layer "B.SilkS"))
    (fp_line (start -0.15 0.4) (end 0.15 0.4)
      (stroke (width 0.15) (type solid)) (layer "B.SilkS"))
    (fp_rect (start -1.25 0.65) (end 1.25 -0.65)
      (stroke (width 0.05) (type solid)) (fill none) (layer "B.CrtYd"))
    (fp_rect (start -0.8 0.4) (end 0.8 -0.4)
      (stroke (width 0.15) (type solid)) (fill none) (layer "B.Fab"))
    (pad "1" smd roundrect (at -0.7 0 180) (size 0.8 1) (layers "B.Cu" "B.Paste" "B.Mask") (roundrect_rratio 0.2)
      (net 26 "Net-(U4B-VDDIO2)") (pintype "passive"))
    (pad "2" smd roundrect (at 0.7 0 180) (size 0.8 1) (layers "B.Cu" "B.Paste" "B.Mask") (roundrect_rratio 0.2)
      (net 9 "+3V3") (pintype "passive"))
  )
	(footprint "antmicro-footprints:C_0402_1005Metric" (layer "B.Cu")
    (at 139.8 110.1 180)
    (descr "Capacitor SMD 0402")
    (tags "capacitor SMD 0402")
    (property "Author" "Antmicro")
    (property "Dielectric" "X5R")
    (property "License" "Apache-2.0")
    (property "MPN" "GRM155R61H104KE14D")
    (property "Manufacturer" "Murata")
    (property "Public" "False")
    (property "Sheetfile" "channel1.kicad_sch")
    (property "Sheetname" "Channel 1")
    (property "Val" "100n")
    (property "Voltage" "50V")
    (property "ki_description" "SMD Multilayer Ceramic Capacitor, 0.1 µF, 50 V, 0402 [1005 Metric], ± 10%, X5R, GRM Series")
    (property "ki_keywords" "0402, SMT, CAPACITOR, PASSIVE, CERAMIC, MLCC")
    (attr smd)
    (fp_text reference "C3" (at 1.05 -0.21) (layer "B.SilkS")
        (effects (font (size 0.65 0.65) (thickness 0.13)) (justify left bottom mirror))
    )
    (fp_text value "C_100n_0402" (at 0 -1.4) (layer "B.Fab")
        (effects (font (size 0.65 0.65) (thickness 0.13)) (justify left bottom mirror))
    )
    (fp_text user "License: Apache-2.0" (at -0.932 -5.17) (layer "B.Fab") hide
        (effects (font (size 0.7 0.7) (thickness 0.15)) (justify left bottom mirror))
    )
    (fp_text user "Author: Antmicro" (at -0.932 -4.17) (layer "B.Fab") hide
        (effects (font (size 0.7 0.7) (thickness 0.15)) (justify left bottom mirror))
    )
    (fp_text user "${REFERENCE}" (at -0.932 -3.168) (layer "B.Fab") hide
        (effects (font (size 0.7 0.7) (thickness 0.15)) (justify left bottom mirror))
    )
    (fp_rect (start -0.925 0.47) (end 0.925 -0.47)
      (stroke (width 0.05) (type default)) (fill none) (layer "B.CrtYd"))
    (fp_line (start -0.494 -0.248) (end -0.494 0.25)
      (stroke (width 0.15) (type solid)) (layer "B.Fab"))
    (fp_line (start -0.494 0.25) (end 0.504 0.25)
      (stroke (width 0.15) (type solid)) (layer "B.Fab"))
    (fp_line (start 0.504 -0.248) (end -0.494 -0.248)
      (stroke (width 0.15) (type solid)) (layer "B.Fab"))
    (fp_line (start 0.504 0.25) (end 0.504 -0.248)
      (stroke (width 0.15) (type solid)) (layer "B.Fab"))
    (pad "1" smd roundrect (at -0.48 0 180) (size 0.59 0.64) (layers "B.Cu" "B.Paste" "B.Mask") (roundrect_rratio 0.25)
      (net 2 "GND") (pintype "passive"))
    (pad "2" smd roundrect (at 0.48 0 180) (size 0.59 0.64) (layers "B.Cu" "B.Paste" "B.Mask") (roundrect_rratio 0.25)
      (net 4 "Net-(U1C-PCKIN)") (pintype "passive"))
  )
	(footprint "antmicro-footprints:TP_SMD_0.75mm" (layer "B.Cu")
    (at 131.4 116.2 180)
    (property "Author" "Antmicro")
    (property "License" "Apache-2.0")
    (property "MPN" "")
    (property "Manufacturer" "")
    (property "Public" "False")
    (property "Sheetfile" "channel1.kicad_sch")
    (property "Sheetname" "Channel 1")
    (property "exclude_from_bom" "")
    (property "ki_description" "SMT test point")
    (property "ki_keywords" "TESTPOINT")
    (attr exclude_from_pos_files exclude_from_bom)
    (fp_text reference "TP1" (at -2.53 -0.38) (layer "B.SilkS")
        (effects (font (size 0.65 0.65) (thickness 0.13)) (justify left bottom mirror))
    )
    (fp_text value "TP_0.75mm_SMD" (at 0 -1.2) (layer "B.Fab")
        (effects (font (size 0.65 0.65) (thickness 0.13)) (justify left bottom mirror))
    )
    (fp_text user "Author: Antmicro" (at -0.4 -3.901) (layer "B.Fab") hide
        (effects (font (size 0.7 0.7) (thickness 0.15)) (justify left bottom mirror))
    )
    (fp_text user "License: Apache-2.0" (at -0.4 -5.101) (layer "B.Fab") hide
        (effects (font (size 0.7 0.7) (thickness 0.15)) (justify left bottom mirror))
    )
    (fp_text user "${REFERENCE}" (at -0.4 -2.7) (layer "B.Fab") hide
        (effects (font (size 0.7 0.7) (thickness 0.15)) (justify left bottom mirror))
    )
    (pad "1" smd circle (at 0 0 180) (size 0.75 0.75) (layers "B.Cu" "B.Mask")
      (net 116 "Net-(U1A-EDID_SDA)") (pinfunction "1") (pintype "passive"))
  )
	(footprint "antmicro-footprints:TP_SMD_0.75mm" (layer "B.Cu")
    (at 155.4 116.2508 180)
    (property "Author" "Antmicro")
    (property "License" "Apache-2.0")
    (property "MPN" "")
    (property "Manufacturer" "")
    (property "Public" "False")
    (property "Sheetfile" "channel2.kicad_sch")
    (property "Sheetname" "Channel 2")
    (property "exclude_from_bom" "")
    (property "ki_description" "SMT test point")
    (property "ki_keywords" "TESTPOINT")
    (attr exclude_from_pos_files exclude_from_bom)
    (fp_text reference "TP5" (at -2.68 -0.3692) (layer "B.SilkS")
        (effects (font (size 0.65 0.65) (thickness 0.13)) (justify left bottom mirror))
    )
    (fp_text value "TP_0.75mm_SMD" (at 0 -1.2) (layer "B.Fab")
        (effects (font (size 0.65 0.65) (thickness 0.13)) (justify left bottom mirror))
    )
    (fp_text user "Author: Antmicro" (at -0.4 -3.901) (layer "B.Fab") hide
        (effects (font (size 0.7 0.7) (thickness 0.15)) (justify left bottom mirror))
    )
    (fp_text user "License: Apache-2.0" (at -0.4 -5.101) (layer "B.Fab") hide
        (effects (font (size 0.7 0.7) (thickness 0.15)) (justify left bottom mirror))
    )
    (fp_text user "${REFERENCE}" (at -0.4 -2.7) (layer "B.Fab") hide
        (effects (font (size 0.7 0.7) (thickness 0.15)) (justify left bottom mirror))
    )
    (pad "1" smd circle (at 0 0 180) (size 0.75 0.75) (layers "B.Cu" "B.Mask")
      (net 120 "Net-(U4A-EDID_SDA)") (pinfunction "1") (pintype "passive"))
  )
	(footprint "antmicro-footprints:R_0402_1005Metric" (layer "B.Cu")
    (at 131.1 112.2 180)
    (descr "Resistor SMD 0402")
    (tags "resistor SMD 0402")
    (property "Author" "Antmicro")
    (property "License" "Apache-2.0")
    (property "MPN" "CR0402-FX-1002GLF")
    (property "Manufacturer" "Bourns")
    (property "Public" "False")
    (property "Sheetfile" "channel1.kicad_sch")
    (property "Sheetname" "Channel 1")
    (property "Tolerance" "1%")
    (property "Val" "10k")
    (property "ki_description" "SMD Chip Resistor, 10 kohm, ± 1%, 62.5 mW, 0402 [1005 Metric], Thick Film, General Purpose")
    (property "ki_keywords" "0402, SMT, RESISTOR, PASSIVE")
    (attr smd)
    (fp_text reference "R3" (at 0.8 -0.3) (layer "B.SilkS")
        (effects (font (size 0.65 0.65) (thickness 0.13)) (justify left bottom mirror))
    )
    (fp_text value "R_10k_0402" (at 0 -1.4) (layer "B.Fab")
        (effects (font (size 0.65 0.65) (thickness 0.13)) (justify left bottom mirror))
    )
    (fp_text user "License: Apache-2.0" (at -0.95 -5.169) (layer "B.Fab") hide
        (effects (font (size 0.7 0.7) (thickness 0.15)) (justify left bottom mirror))
    )
    (fp_text user "Author: Antmicro" (at -0.95 -4.169) (layer "B.Fab") hide
        (effects (font (size 0.7 0.7) (thickness 0.15)) (justify left bottom mirror))
    )
    (fp_text user "${REFERENCE}" (at -0.95 -3.168) (layer "B.Fab") hide
        (effects (font (size 0.7 0.7) (thickness 0.15)) (justify left bottom mirror))
    )
    (fp_rect (start -0.925 0.47) (end 0.925 -0.47)
      (stroke (width 0.05) (type default)) (fill none) (layer "B.CrtYd"))
    (fp_rect (start -0.5 0.25) (end 0.5 -0.25)
      (stroke (width 0.15) (type solid)) (fill none) (layer "B.Fab"))
    (pad "1" smd roundrect (at -0.48 0 180) (size 0.59 0.64) (layers "B.Cu" "B.Paste" "B.Mask") (roundrect_rratio 0.25)
      (net 98 "/Channel 1/CH1_~{RST}") (pintype "passive"))
    (pad "2" smd roundrect (at 0.48 0 180) (size 0.59 0.64) (layers "B.Cu" "B.Paste" "B.Mask") (roundrect_rratio 0.25)
      (net 9 "+3V3") (pintype "passive"))
  )
	(footprint "antmicro-footprints:TP_SMD_0.75mm" (layer "B.Cu")
    (at 167.7 102.4508 180)
    (property "Author" "Antmicro")
    (property "License" "Apache-2.0")
    (property "MPN" "")
    (property "Manufacturer" "")
    (property "Public" "False")
    (property "Sheetfile" "channel2.kicad_sch")
    (property "Sheetname" "Channel 2")
    (property "exclude_from_bom" "")
    (property "ki_description" "SMT test point")
    (property "ki_keywords" "TESTPOINT")
    (attr exclude_from_pos_files exclude_from_bom)
    (fp_text reference "TP8" (at 0 0.6) (layer "B.SilkS")
        (effects (font (size 0.65 0.65) (thickness 0.13)) (justify left bottom mirror))
    )
    (fp_text value "TP_0.75mm_SMD" (at 0 -1.2) (layer "B.Fab")
        (effects (font (size 0.65 0.65) (thickness 0.13)) (justify left bottom mirror))
    )
    (fp_text user "Author: Antmicro" (at -0.4 -3.901) (layer "B.Fab") hide
        (effects (font (size 0.7 0.7) (thickness 0.15)) (justify left bottom mirror))
    )
    (fp_text user "License: Apache-2.0" (at -0.4 -5.101) (layer "B.Fab") hide
        (effects (font (size 0.7 0.7) (thickness 0.15)) (justify left bottom mirror))
    )
    (fp_text user "${REFERENCE}" (at -0.4 -2.7) (layer "B.Fab") hide
        (effects (font (size 0.7 0.7) (thickness 0.15)) (justify left bottom mirror))
    )
    (pad "1" smd circle (at 0 0 180) (size 0.75 0.75) (layers "B.Cu" "B.Mask")
      (net 122 "Net-(U6-EN)") (pinfunction "1") (pintype "passive"))
  )
	(footprint "antmicro-footprints:C_0402_1005Metric" (layer "B.Cu")
    (at 163.8 108.15 180)
    (descr "Capacitor SMD 0402")
    (tags "capacitor SMD 0402")
    (property "Author" "Antmicro")
    (property "Dielectric" "X5R")
    (property "License" "Apache-2.0")
    (property "MPN" "GRM155R61H104KE14D")
    (property "Manufacturer" "Murata")
    (property "Public" "False")
    (property "Sheetfile" "channel2.kicad_sch")
    (property "Sheetname" "Channel 2")
    (property "Val" "100n")
    (property "Voltage" "50V")
    (property "ki_description" "SMD Multilayer Ceramic Capacitor, 0.1 µF, 50 V, 0402 [1005 Metric], ± 10%, X5R, GRM Series")
    (property "ki_keywords" "0402, SMT, CAPACITOR, PASSIVE, CERAMIC, MLCC")
    (attr smd)
    (fp_text reference "C24" (at 0.9 -0.35) (layer "B.SilkS")
        (effects (font (size 0.65 0.65) (thickness 0.13)) (justify left bottom mirror))
    )
    (fp_text value "C_100n_0402" (at 0 -1.4) (layer "B.Fab")
        (effects (font (size 0.65 0.65) (thickness 0.13)) (justify left bottom mirror))
    )
    (fp_text user "${REFERENCE}" (at -0.932 -3.168) (layer "B.Fab") hide
        (effects (font (size 0.7 0.7) (thickness 0.15)) (justify left bottom mirror))
    )
    (fp_text user "Author: Antmicro" (at -0.932 -4.17) (layer "B.Fab") hide
        (effects (font (size 0.7 0.7) (thickness 0.15)) (justify left bottom mirror))
    )
    (fp_text user "License: Apache-2.0" (at -0.932 -5.17) (layer "B.Fab") hide
        (effects (font (size 0.7 0.7) (thickness 0.15)) (justify left bottom mirror))
    )
    (fp_rect (start -0.925 0.47) (end 0.925 -0.47)
      (stroke (width 0.05) (type default)) (fill none) (layer "B.CrtYd"))
    (fp_line (start -0.494 -0.248) (end -0.494 0.25)
      (stroke (width 0.15) (type solid)) (layer "B.Fab"))
    (fp_line (start -0.494 0.25) (end 0.504 0.25)
      (stroke (width 0.15) (type solid)) (layer "B.Fab"))
    (fp_line (start 0.504 -0.248) (end -0.494 -0.248)
      (stroke (width 0.15) (type solid)) (layer "B.Fab"))
    (fp_line (start 0.504 0.25) (end 0.504 -0.248)
      (stroke (width 0.15) (type solid)) (layer "B.Fab"))
    (pad "1" smd roundrect (at -0.48 0 180) (size 0.59 0.64) (layers "B.Cu" "B.Paste" "B.Mask") (roundrect_rratio 0.25)
      (net 2 "GND") (pintype "passive"))
    (pad "2" smd roundrect (at 0.48 0 180) (size 0.59 0.64) (layers "B.Cu" "B.Paste" "B.Mask") (roundrect_rratio 0.25)
      (net 16 "Net-(U4C-BIASDA)") (pintype "passive"))
  )
	(footprint "antmicro-footprints:C_0402_1005Metric" (layer "B.Cu")
    (at 163.8 109.15 180)
    (descr "Capacitor SMD 0402")
    (tags "capacitor SMD 0402")
    (property "Author" "Antmicro")
    (property "Dielectric" "X5R")
    (property "License" "Apache-2.0")
    (property "MPN" "GRM155R61H104KE14D")
    (property "Manufacturer" "Murata")
    (property "Public" "False")
    (property "Sheetfile" "channel2.kicad_sch")
    (property "Sheetname" "Channel 2")
    (property "Val" "100n")
    (property "Voltage" "50V")
    (property "ki_description" "SMD Multilayer Ceramic Capacitor, 0.1 µF, 50 V, 0402 [1005 Metric], ± 10%, X5R, GRM Series")
    (property "ki_keywords" "0402, SMT, CAPACITOR, PASSIVE, CERAMIC, MLCC")
    (attr smd)
    (fp_text reference "C25" (at 0.92 -0.29) (layer "B.SilkS")
        (effects (font (size 0.65 0.65) (thickness 0.13)) (justify left bottom mirror))
    )
    (fp_text value "C_100n_0402" (at 0 -1.4) (layer "B.Fab")
        (effects (font (size 0.65 0.65) (thickness 0.13)) (justify left bottom mirror))
    )
    (fp_text user "License: Apache-2.0" (at -0.932 -5.17) (layer "B.Fab") hide
        (effects (font (size 0.7 0.7) (thickness 0.15)) (justify left bottom mirror))
    )
    (fp_text user "${REFERENCE}" (at -0.932 -3.168) (layer "B.Fab") hide
        (effects (font (size 0.7 0.7) (thickness 0.15)) (justify left bottom mirror))
    )
    (fp_text user "Author: Antmicro" (at -0.932 -4.17) (layer "B.Fab") hide
        (effects (font (size 0.7 0.7) (thickness 0.15)) (justify left bottom mirror))
    )
    (fp_rect (start -0.925 0.47) (end 0.925 -0.47)
      (stroke (width 0.05) (type default)) (fill none) (layer "B.CrtYd"))
    (fp_line (start -0.494 -0.248) (end -0.494 0.25)
      (stroke (width 0.15) (type solid)) (layer "B.Fab"))
    (fp_line (start -0.494 0.25) (end 0.504 0.25)
      (stroke (width 0.15) (type solid)) (layer "B.Fab"))
    (fp_line (start 0.504 -0.248) (end -0.494 -0.248)
      (stroke (width 0.15) (type solid)) (layer "B.Fab"))
    (fp_line (start 0.504 0.25) (end 0.504 -0.248)
      (stroke (width 0.15) (type solid)) (layer "B.Fab"))
    (pad "1" smd roundrect (at -0.48 0 180) (size 0.59 0.64) (layers "B.Cu" "B.Paste" "B.Mask") (roundrect_rratio 0.25)
      (net 2 "GND") (pintype "passive"))
    (pad "2" smd roundrect (at 0.48 0 180) (size 0.59 0.64) (layers "B.Cu" "B.Paste" "B.Mask") (roundrect_rratio 0.25)
      (net 17 "Net-(U4C-DAOUT)") (pintype "passive"))
  )
	(footprint "antmicro-footprints:R_0603_1608Metric" (layer "B.Cu")
    (at 154.8 110.9 180)
    (descr "Resistor SMD 0603")
    (tags "resistor SMD 0603")
    (property "Author" "Antmicro")
    (property "Current" "1A")
    (property "License" "Apache-2.0")
    (property "MPN" "CR0603-J/-000ELF")
    (property "Manufacturer" "Bourns")
    (property "Public" "False")
    (property "Sheetfile" "channel2.kicad_sch")
    (property "Sheetname" "Channel 2")
    (property "Tolerance" "")
    (property "Val" "0R")
    (property "ki_description" "Zero Ohm Resistor, Jumper, 0603 [1608 Metric], Thick Film, 100 mW, 1 A, Surface Mount Device, CR")
    (property "ki_keywords" "0603, SMT, RESISTOR, PASSIVE")
    (attr smd)
    (fp_text reference "R19" (at 1 -0.4) (layer "B.SilkS")
        (effects (font (size 0.7 0.7) (thickness 0.15)) (justify left bottom mirror))
    )
    (fp_text value "R_0R_0603" (at 0 -1.6) (layer "B.Fab")
        (effects (font (size 0.7 0.7) (thickness 0.15)) (justify left bottom mirror))
    )
    (fp_text user "${REFERENCE}" (at -1.25 -3.898) (layer "B.Fab") hide
        (effects (font (size 0.7 0.7) (thickness 0.15)) (justify left bottom mirror))
    )
    (fp_text user "License: Apache-2.0" (at -1.25 -5.9) (layer "B.Fab") hide
        (effects (font (size 0.7 0.7) (thickness 0.15)) (justify left bottom mirror))
    )
    (fp_text user "Author: Antmicro" (at -1.25 -4.9) (layer "B.Fab") hide
        (effects (font (size 0.7 0.7) (thickness 0.15)) (justify left bottom mirror))
    )
    (fp_line (start -0.15 -0.4) (end 0.15 -0.4)
      (stroke (width 0.15) (type solid)) (layer "B.SilkS"))
    (fp_line (start -0.15 0.4) (end 0.15 0.4)
      (stroke (width 0.15) (type solid)) (layer "B.SilkS"))
    (fp_rect (start -1.25 0.65) (end 1.25 -0.65)
      (stroke (width 0.05) (type solid)) (fill none) (layer "B.CrtYd"))
    (fp_rect (start -0.8 0.4) (end 0.8 -0.4)
      (stroke (width 0.15) (type solid)) (fill none) (layer "B.Fab"))
    (pad "1" smd roundrect (at -0.7 0 180) (size 0.8 1) (layers "B.Cu" "B.Paste" "B.Mask") (roundrect_rratio 0.2)
      (net 23 "Net-(U4B-VDDIO1)") (pintype "passive"))
    (pad "2" smd roundrect (at 0.7 0 180) (size 0.8 1) (layers "B.Cu" "B.Paste" "B.Mask") (roundrect_rratio 0.2)
      (net 9 "+3V3") (pintype "passive"))
  )
	(footprint "antmicro-footprints:TP_SMD_0.75mm" (layer "B.Cu")
    (at 130.3 103.1 180)
    (property "Author" "Antmicro")
    (property "License" "Apache-2.0")
    (property "MPN" "")
    (property "Manufacturer" "")
    (property "Public" "False")
    (property "Sheetfile" "channel1.kicad_sch")
    (property "Sheetname" "Channel 1")
    (property "exclude_from_bom" "")
    (property "ki_description" "SMT test point")
    (property "ki_keywords" "TESTPOINT")
    (attr exclude_from_pos_files exclude_from_bom)
    (fp_text reference "TP3" (at 0 0.6) (layer "B.SilkS")
        (effects (font (size 0.65 0.65) (thickness 0.13)) (justify left bottom mirror))
    )
    (fp_text value "TP_0.75mm_SMD" (at 0 -1.2) (layer "B.Fab")
        (effects (font (size 0.65 0.65) (thickness 0.13)) (justify left bottom mirror))
    )
    (fp_text user "License: Apache-2.0" (at -0.4 -5.101) (layer "B.Fab") hide
        (effects (font (size 0.7 0.7) (thickness 0.15)) (justify left bottom mirror))
    )
    (fp_text user "Author: Antmicro" (at -0.4 -3.901) (layer "B.Fab") hide
        (effects (font (size 0.7 0.7) (thickness 0.15)) (justify left bottom mirror))
    )
    (fp_text user "${REFERENCE}" (at -0.4 -2.7) (layer "B.Fab") hide
        (effects (font (size 0.7 0.7) (thickness 0.15)) (justify left bottom mirror))
    )
    (pad "1" smd circle (at 0 0 180) (size 0.75 0.75) (layers "B.Cu" "B.Mask")
      (net 115 "/Channel 1/HDMI1_HPDO") (pinfunction "1") (pintype "passive"))
  )
)
